# T6G (Grand Teton) — schematic netlist excerpt (pin names and nets, part order shuffled) for the footprints in the layout excerpt that follows; sources: Cadence DE-HDL packaged netlist, KiCad conversion of 04192023_DAF0TMB3IC0_F0TG_MB_C_brd_V02_OCP.brd

R6136  Q_RES  1K 1% CHIP  pkg 0402LF  page 84 : A = P3V3_AUX ; B = FM_BOARD_BMC_SKU_ID4
R1190  Q_RES  1K 1% CHIP  pkg 0402LF  page 83 : A = PVDD11_S3_P1_PMALERT ; B = P3V3_AUX

(kicad_pcb
	(version 20260206)
	(generator "pcbnew")
	(generator_version "10.0")
	(general
		(thickness 1.6)
		(legacy_teardrops no)
	)
	(paper "A4")
	(title_block
		(title "04192023_DAF0TMB3IC0_F0TG_MB_C_brd_V02_OCP.brd")
		(comment 1 "Grand Teton / footprints 793-794 of 8354")
	)
	(layers
		(0 "F.Cu" signal "TOP")
		(4 "In1.Cu" signal "GND")
		(6 "In2.Cu" signal "IN1")
		(8 "In3.Cu" signal "GND1")
		(10 "In4.Cu" signal "IN2")
		(12 "In5.Cu" signal "GND2")
		(14 "In6.Cu" signal "IN3")
		(16 "In7.Cu" signal "GND3")
		(18 "In8.Cu" signal "VCC")
		(20 "In9.Cu" signal "VCC1")
		(22 "In10.Cu" signal "GND4")
		(24 "In11.Cu" signal "IN4")
		(26 "In12.Cu" signal "GND5")
		(28 "In13.Cu" signal "IN5")
		(30 "In14.Cu" signal "GND6")
		(32 "In15.Cu" signal "IN6")
		(34 "In16.Cu" signal "GND7")
		(2 "B.Cu" signal "BOTTOM")
		(9 "F.Adhes" user "F.Adhesive")
		(11 "B.Adhes" user "B.Adhesive")
		(13 "F.Paste" user "Package Geometry/Pastemask Top")
		(15 "B.Paste" user "Package Geometry/Pastemask Bottom")
		(5 "F.SilkS" user "Ref Des/Silkscreen Top")
		(7 "B.SilkS" user "Ref Des/Silkscreen Bottom")
		(1 "F.Mask" user "Board Geometry/Soldermask Top")
		(3 "B.Mask" user "Board Geometry/Soldermask Bottom")
		(17 "Dwgs.User" user "User.Drawings")
		(19 "Cmts.User" user "User.Comments")
		(21 "Eco1.User" user "User.Eco1")
		(23 "Eco2.User" user "User.Eco2")
		(25 "Edge.Cuts" user "Board Geometry/Outline")
		(27 "Margin" user)
		(31 "F.CrtYd" user "Package Geometry/Place Bound Top")
		(29 "B.CrtYd" user "Package Geometry/Place Bound Bottom")
		(35 "F.Fab" user "Ref Des/Assembly Top")
		(33 "B.Fab" user "Ref Des/Assembly Bottom")
	)
	(footprint ""
		(layer "F.Cu")
		(at 185.801 -100.294948 -90)
		(property "Reference" "R1190"
			(at 0 0 270)
			(layer "F.SilkS")
			(hide yes)
			(effects
				(font
					(size 1.27 1.27)
				)
			)
		)
		(property "Value" ""
			(at 0 0 270)
			(layer "F.Fab")
			(effects
				(font
					(size 1.27 1.27)
				)
			)
		)
		(duplicate_pad_numbers_are_jumpers no)
		(fp_line
			(start -0.7874 0.4064)
			(end -0.7874 -0.4064)
			(stroke
				(width 0.1524)
				(type default)
			)
			(layer "F.SilkS")
		)
		(fp_line
			(start 0.7874 0.4064)
			(end -0.7874 0.4064)
			(stroke
				(width 0.1524)
				(type default)
			)
			(layer "F.SilkS")
		)
		(fp_line
			(start -0.7874 -0.4064)
			(end 0.7874 -0.4064)
			(stroke
				(width 0.1524)
				(type default)
			)
			(layer "F.SilkS")
		)
		(fp_line
			(start 0.7874 -0.4064)
			(end 0.7874 0.4064)
			(stroke
				(width 0.1524)
				(type default)
			)
			(layer "F.SilkS")
		)
		(fp_line
			(start -0.67945 0.3048)
			(end -0.67945 -0.305054)
			(stroke
				(width 0.1)
				(type default)
			)
			(layer "F.Fab")
		)
		(fp_line
			(start -0.12065 0.3048)
			(end -0.67945 0.3048)
			(stroke
				(width 0.1)
				(type default)
			)
			(layer "F.Fab")
		)
		(fp_line
			(start 0.120396 0.3048)
			(end 0.120396 0.2794)
			(stroke
				(width 0.1)
				(type default)
			)
			(layer "F.Fab")
		)
		(fp_line
			(start 0.67945 0.3048)
			(end 0.120396 0.3048)
			(stroke
				(width 0.1)
				(type default)
			)
			(layer "F.Fab")
		)
		(fp_line
			(start -0.12065 0.2794)
			(end -0.12065 0.3048)
			(stroke
				(width 0.1)
				(type default)
			)
			(layer "F.Fab")
		)
		(fp_line
			(start 0.120396 0.2794)
			(end -0.12065 0.2794)
			(stroke
				(width 0.1)
				(type default)
			)
			(layer "F.Fab")
		)
		(fp_line
			(start -0.12065 -0.2794)
			(end 0.12065 -0.2794)
			(stroke
				(width 0.1)
				(type default)
			)
			(layer "F.Fab")
		)
		(fp_line
			(start 0.12065 -0.2794)
			(end 0.12065 -0.3048)
			(stroke
				(width 0.1)
				(type default)
			)
			(layer "F.Fab")
		)
		(fp_line
			(start 0.12065 -0.3048)
			(end 0.67945 -0.3048)
			(stroke
				(width 0.1)
				(type default)
			)
			(layer "F.Fab")
		)
		(fp_line
			(start 0.67945 -0.3048)
			(end 0.67945 0.3048)
			(stroke
				(width 0.1)
				(type default)
			)
			(layer "F.Fab")
		)
		(fp_line
			(start -0.67945 -0.305054)
			(end -0.12065 -0.305054)
			(stroke
				(width 0.1)
				(type default)
			)
			(layer "F.Fab")
		)
		(fp_line
			(start -0.12065 -0.305054)
			(end -0.12065 -0.2794)
			(stroke
				(width 0.1)
				(type default)
			)
			(layer "F.Fab")
		)
		(pad "1" smd circle
			(at -0.40005 0 270)
			(size 0 0)
			(layers "F.Cu" "F.Mask" "F.Paste")
			(net "PVDD11_S3_P1_PMALERT")
		)
		(pad "2" smd circle
			(at 0.40005 0 270)
			(size 0 0)
			(layers "F.Cu" "F.Mask" "F.Paste")
			(net "P3V3_AUX")
		)
	)
	(footprint ""
		(layer "F.Cu")
		(at 167.112442 -116.26977)
		(property "Reference" "R6136"
			(at 0 0 0)
			(layer "F.SilkS")
			(hide yes)
			(effects
				(font
					(size 1.27 1.27)
				)
			)
		)
		(property "Value" ""
			(at 0 0 0)
			(layer "F.Fab")
			(effects
				(font
					(size 1.27 1.27)
				)
			)
		)
		(duplicate_pad_numbers_are_jumpers no)
		(fp_line
			(start -0.7874 -0.4064)
			(end 0.7874 -0.4064)
			(stroke
				(width 0.1524)
				(type default)
			)
			(layer "F.SilkS")
		)
		(fp_line
			(start -0.7874 0.4064)
			(end -0.7874 -0.4064)
			(stroke
				(width 0.1524)
				(type default)
			)
			(layer "F.SilkS")
		)
		(fp_line
			(start 0.7874 -0.4064)
			(end 0.7874 0.4064)
			(stroke
				(width 0.1524)
				(type default)
			)
			(layer "F.SilkS")
		)
		(fp_line
			(start 0.7874 0.4064)
			(end -0.7874 0.4064)
			(stroke
				(width 0.1524)
				(type default)
			)
			(layer "F.SilkS")
		)
		(fp_line
			(start -0.67945 -0.305054)
			(end -0.12065 -0.305054)
			(stroke
				(width 0.1)
				(type default)
			)
			(layer "F.Fab")
		)
		(fp_line
			(start -0.67945 0.3048)
			(end -0.67945 -0.305054)
			(stroke
				(width 0.1)
				(type default)
			)
			(layer "F.Fab")
		)
		(fp_line
			(start -0.12065 -0.305054)
			(end -0.12065 -0.2794)
			(stroke
				(width 0.1)
				(type default)
			)
			(layer "F.Fab")
		)
		(fp_line
			(start -0.12065 -0.2794)
			(end 0.12065 -0.2794)
			(stroke
				(width 0.1)
				(type default)
			)
			(layer "F.Fab")
		)
		(fp_line
			(start -0.12065 0.2794)
			(end -0.12065 0.3048)
			(stroke
				(width 0.1)
				(type default)
			)
			(layer "F.Fab")
		)
		(fp_line
			(start -0.12065 0.3048)
			(end -0.67945 0.3048)
			(stroke
				(width 0.1)
				(type default)
			)
			(layer "F.Fab")
		)
		(fp_line
			(start 0.120396 0.2794)
			(end -0.12065 0.2794)
			(stroke
				(width 0.1)
				(type default)
			)
			(layer "F.Fab")
		)
		(fp_line
			(start 0.120396 0.3048)
			(end 0.120396 0.2794)
			(stroke
				(width 0.1)
				(type default)
			)
			(layer "F.Fab")
		)
		(fp_line
			(start 0.12065 -0.3048)
			(end 0.67945 -0.3048)
			(stroke
				(width 0.1)
				(type default)
			)
			(layer "F.Fab")
		)
		(fp_line
			(start 0.12065 -0.2794)
			(end 0.12065 -0.3048)
			(stroke
				(width 0.1)
				(type default)
			)
			(layer "F.Fab")
		)
		(fp_line
			(start 0.67945 -0.3048)
			(end 0.67945 0.3048)
			(stroke
				(width 0.1)
				(type default)
			)
			(layer "F.Fab")
		)
		(fp_line
			(start 0.67945 0.3048)
			(end 0.120396 0.3048)
			(stroke
				(width 0.1)
				(type default)
			)
			(layer "F.Fab")
		)
		(pad "1" smd circle
			(at -0.40005 0)
			(size 0 0)
			(layers "F.Cu" "F.Mask" "F.Paste")
			(net "P3V3_AUX")
		)
		(pad "2" smd circle
			(at 0.40005 0)
			(size 0 0)
			(layers "F.Cu" "F.Mask" "F.Paste")
			(net "FM_BOARD_BMC_SKU_ID4")
		)
	)
)
